FILE_TYPE = CONNECTIVITY;
{Allegro Design Entry HDL 17.4-2019 S026 (4007227) 1/17/2022}
"PAGE_NUMBER" = 194;
0"NC";
1"GND\g";
2"GND\g";
3"GND\g";
4"GND\g";
5"GND\g";
6"GND\g";
7"GND\g";
8"GND\g";
9"GND\g";
10"GND\g";
11"GND\g";
12"SW_P12V_AUX_PVDDCR_CPU1_P1_FLT\g";
13"PVDDCR_CPU1_P1_VOS3";
14"SW_PVDDCR_CPU1_P1_SW3";
15"SW_PVDDCR_CPU1_P1_BOOTR3";
16"GND\g";
17"SW_PVDDCR_CPU1_P1_BOOT3_R";
18"SW_PVDDCR_CPU1_P1_BOOT4";
19"SW_PVDDCR_CPU1_P1_BOOT4_R";
20"SW_PVDDCR_CPU1_P1_BOOT3";
21"PVDDCR_CPU1_P1\g";
22"GND\g";
23"PVDDCR_CPU1_P1\g";
24"GND\g";
25"SW_P12V_AUX_PVDDCR_CPU1_P1_FLT\g";
26"GND\g";
27"PVDDCR_CPU1_P1_PVCC\g";
28"GND\g";
29"GND\g";
30"PVDDCR_CPU1_P1_PVCC\g";
31"PVDDCR_CPU1_P1_IMON4";
32"PVDDCR_CPU1_P1_VCC4";
33"SW_PVDDCR_CPU1_P1_SW3_RC";
34"PVDDCR_CPU1_P1_VOS4";
35"NC_PVDDCR_CPU1_P1_GL2_4";
36"SW_PVDDCR_CPU1_P1_BOOTR4";
37"SW_PVDDCR_CPU1_P1_SW4";
38"NC_PVDDCR_CPU1_P1_GL1_3";
39"NC_PVDDCR_CPU1_P1_GL2_3";
40"IND_CPU1_P1_CPL3";
41"IND_CPU1_P1_CPL2";
42"IND_CPU1_P1_CPL3";
43"SW_PVDDCR_CPU1_P1_SW4_RC";
44"NC_PVDDCR_CPU1_P1_GL1_4";
45"PVDDCR_CPU1_P1_VCC3";
46"NC_PVDDCR_CPU1_P1_DNC3";
47"PVDDCR_CPU1_P1_VCCS"CDS_PHYS_NET_NAME"PVDDCR_CPU1_P1_VCCS";
48"PVDDCR_CPU1_P1_IMON3";
49"PVDDCR_CPU1_P1_LSET3";
50"NC_PVDDCR_CPU1_P1_DNC4";
51"PVDDCR_CPU1_P1_VCCS"CDS_PHYS_NET_NAME"PVDDCR_CPU1_P1_VCCS";
52"PVDDCR_CPU1_P1_TEMP0";
53"PVDDCR_CPU1_P1_PWM4";
54"PVDDCR_CPU1_P1_PWM3";
55"PVDDCR_CPU1_P1_TEMP0";
56"PVDDCR_CPU1_P1_LSET4";
%"UNIVERSAL_GND"
"1","(850,900)","0","pure_quanta_power","I1";
;
CDS_LIB"pure_quanta_power"
HDL_POWER"GND";
"A"1;
%"UNIVERSAL_GND"
"1","(875,3725)","0","pure_quanta_power","I11";
;
CDS_LIB"pure_quanta_power"
HDL_POWER"GND";
"A"2;
%"Q_CAP"
"1","(875,3925)","0","pure_quanta","I12";
;
LOCATION"PC404_3"
$SEC"1"
CDS_SEC"1"
MATERIAL"X7R"
TOLERANCE"10%"
VALUE"0.1UF"
VOLTAGE"25V"
PACK_TYPE"0402"
CDS_LIB"pure_quanta"
PART_NUMBER"CH4104K1B00";
"B"
$PN"2"2;
"A"
$PN"1"47;
%"Q_RES"
"2","(1500,2475)","0","pure_quanta","I13";
;
LOCATION"PR264"
$SEC"1"
CDS_SEC"1"
PACK_TYPE"0402LF"
VALUE"2.2"
TOLERANCE"1%"
MATERIAL"CHIP"
WATTAGE"1/16W"
CDS_LIB"pure_quanta"
PART_NUMBER"CS-2202FB01";
"A"
$PN"1"30;
"B"
$PN"2"32;
%"VCC_CORE"
"1","(1500,2875)","0","pure_quanta_power","I14";
;
HDL_POWER"PVDDCR_CPU1_P1_PVCC"
CDS_LIB"pure_quanta_power";
"A"30;
%"UNIVERSAL_GND"
"1","(1850,2225)","0","pure_quanta_power","I15";
;
CDS_LIB"pure_quanta_power"
HDL_POWER"GND";
"A"3;
%"Q_CAP"
"1","(1850,2500)","0","pure_quanta","I16";
;
LOCATION"PC401_C1P1_4"
$SEC"1"
CDS_SEC"1"
TOLERANCE"10%"
VALUE"2.2UF"
PACK_TYPE"C0402"
MATERIAL"X6S"
VOLTAGE"10V"
CDS_LIB"pure_quanta"
PART_NUMBER"CH5222KEB01";
"B"
$PN"2"3;
"A"
$PN"1"30;
%"UNIVERSAL_GND"
"1","(1375,3575)","0","pure_quanta_power","I17";
;
CDS_LIB"pure_quanta_power"
HDL_POWER"GND";
"A"4;
%"Q_RES"
"2","(1375,3800)","2","pure_quanta","I18";
;
LOCATION"PR263"
$SEC"1"
CDS_SEC"1"
MATERIAL"EMPTY"
TOLERANCE"1%"
VALUE"8.87K"
WATTAGE"1/16W"
PACK_TYPE"0402LF"
CDS_LIB"pure_quanta"
PART_NUMBER"CS28872FB01";
"A"
$PN"1"49;
"B"
$PN"2"4;
%"Q_CAP"
"1","(850,1100)","0","pure_quanta","I2";
;
LOCATION"PC403_4"
$SEC"1"
CDS_SEC"1"
MATERIAL"X7R"
TOLERANCE"10%"
VALUE"0.1UF"
VOLTAGE"25V"
PACK_TYPE"0402"
CDS_LIB"pure_quanta"
PART_NUMBER"CH4104K1B00";
"B"
$PN"2"1;
"A"
$PN"1"51;
%"ISL99390FRZTR5935"
"1","(3275,1475)","0","pure_quanta","I21";
;
LOCATION"PU36"
$SEC"1"
CDS_SEC"1"
PART_TYPE"SMLF"
MATERIAL"IC"
VALUE"ISL99390FRZ-TR5935"
CDS_LIB"pure_quanta"
CDS_LMAN_SYM_OUTLINE"-300,700,250,-650"
NEEDS_NO_SIZE"TRUE"
PART_NUMBER"AL099390004";
"PGND2"
$PN"7_9-20_24"29;
"GL2"
$PN"41"35;
"GL1"
$PN"6"44;
"DNC"
$PN"31"50;
"EN"
$PN"35"32;
"PGND3"
$PN"40"29;
"VOS"
$PN"1"34;
"VIN2"
$PN"30"12;
"PGND1"
$PN"5"29;
"SW"
$PN"10_19"37;
"LSET"
$PN"37"56;
"IOUT"
$PN"38"31;
"TOUT_FLT"
$PN"36"52;
"PVCC"
$PN"4"30;
"PHASE"
$PN"32"36;
"VIN1"
$PN"25_29"12;
"BOOT"
$PN"33"18;
"AGND"
$PN"2"29;
"VCC"
$PN"3"32;
"REFIN"
$PN"39"51;
"PWM"
$PN"34"53;
%"UNIVERSAL_GND"
"1","(3925,750)","0","pure_quanta_power","I22";
;
CDS_LIB"pure_quanta_power"
HDL_POWER"GND";
"A"29;
%"Q_CAP"
"1","(4075,2400)","0","pure_quanta","I23";
;
LOCATION"PC405_4"
$SEC"1"
CDS_SEC"1"
MATERIAL"X7R"
TOLERANCE"10%"
VOLTAGE"25V"
VALUE"0.1UF"
PACK_TYPE"0402"
CDS_LIB"pure_quanta"
PART_NUMBER"CH4104K1B00";
"B"
$PN"2"11;
"A"
$PN"1"12;
%"UNIVERSAL_GND"
"1","(3950,3575)","0","pure_quanta_power","I24";
;
CDS_LIB"pure_quanta_power"
HDL_POWER"GND";
"A"28;
%"Q_CAP"
"1","(1675,4750)","0","pure_quanta","I27";
;
LOCATION"PC400"
$SEC"1"
CDS_SEC"1"
MATERIAL"X6S"
TOLERANCE"10%"
VALUE"2.2UF"
VOLTAGE"10V"
PACK_TYPE"C0402"
CDS_LIB"pure_quanta"
PART_NUMBER"CH5222KEB01";
"B"
$PN"2"5;
"A"
$PN"1"45;
%"UNIVERSAL_GND"
"1","(1675,4550)","0","pure_quanta_power","I28";
;
CDS_LIB"pure_quanta_power"
HDL_POWER"GND";
"A"5;
%"Q_RES"
"2","(1675,5300)","0","pure_quanta","I29";
;
LOCATION"PR265"
$SEC"1"
CDS_SEC"1"
VALUE"2.2"
TOLERANCE"1%"
WATTAGE"1/16W"
MATERIAL"CHIP"
PACK_TYPE"0402LF"
CDS_LIB"pure_quanta"
PART_NUMBER"CS-2202FB01";
"A"
$PN"1"27;
"B"
$PN"2"45;
%"UNIVERSAL_GND"
"1","(1350,750)","0","pure_quanta_power","I3";
;
CDS_LIB"pure_quanta_power"
HDL_POWER"GND";
"A"6;
%"UNIVERSAL_GND"
"1","(2025,5050)","0","pure_quanta_power","I30";
;
CDS_LIB"pure_quanta_power"
HDL_POWER"GND";
"A"7;
%"Q_CAP"
"1","(2025,5325)","0","pure_quanta","I31";
;
LOCATION"PC402_C1P1_3"
$SEC"1"
CDS_SEC"1"
MATERIAL"X6S"
TOLERANCE"10%"
VALUE"2.2UF"
VOLTAGE"10V"
PACK_TYPE"C0402"
CDS_LIB"pure_quanta"
PART_NUMBER"CH5222KEB01";
"B"
$PN"2"7;
"A"
$PN"1"27;
%"VCC_CORE"
"1","(1675,5700)","0","pure_quanta_power","I32";
;
HDL_POWER"PVDDCR_CPU1_P1_PVCC"
CDS_LIB"pure_quanta_power";
"A"27;
%"Q_CAP"
"1","(4125,5250)","0","pure_quanta","I33";
;
LOCATION"PC408_3"
$SEC"1"
CDS_SEC"1"
PACK_TYPE"0402"
MATERIAL"X7R"
VALUE"0.1UF"
VOLTAGE"25V"
TOLERANCE"10%"
CDS_LIB"pure_quanta"
PART_NUMBER"CH4104K1B00";
"B"
$PN"2"16;
"A"
$PN"1"25;
%"UNIVERSAL_GND"
"1","(4675,550)","0","pure_quanta_power","I34";
;
CDS_LIB"pure_quanta_power"
HDL_POWER"GND";
"A"8;
%"Q_RES"
"2","(4675,775)","0","pure_quanta","I35";
;
LOCATION"PR515"
$SEC"1"
CDS_SEC"1"
WATTAGE"1/8W"
TOLERANCE"1%"
VALUE"1.5"
PACK_TYPE"0402LF"
MATERIAL"EMPTY"
CDS_LIB"pure_quanta"
PART_NUMBER"CS-1504FB00";
"A"
$PN"1"43;
"B"
$PN"2"8;
%"Q_RES"
"1","(4600,1825)","0","pure_quanta","I36";
;
LOCATION"PR266"
$SEC"1"
CDS_SEC"1"
WATTAGE"1/16W"
PACK_TYPE"0402LF"
TOLERANCE"1%"
MATERIAL"CHIP"
VALUE"5.6"
CDS_LIB"pure_quanta"
PART_NUMBER"CS-5602FB01";
"B"
$PN"2"19;
"A"
$PN"1"18;
%"Q_CAP"
"1","(4675,1275)","0","pure_quanta","I37";
;
LOCATION"PC205"
$SEC"1"
CDS_SEC"1"
MATERIAL"EMPTY"
TOLERANCE"10%"
VALUE"560PF"
VOLTAGE"50V"
PACK_TYPE"C0402"
CDS_LIB"pure_quanta"
PART_NUMBER"CH1566K1B09";
"B"
$PN"2"43;
"A"
$PN"1"37;
%"Q_RES"
"1","(5975,475)","0","pure_quanta","I38";
;
LOCATION"PR268"
$SEC"1"
CDS_SEC"1"
PACK_TYPE"0402LF"
VALUE"0"
TOLERANCE"5%"
MATERIAL"CHIP"
WATTAGE"1/16W"
CDS_LIB"pure_quanta"
PART_NUMBER"CS00002JB13";
"B"
$PN"2"23;
"A"
$PN"1"34;
%"Q_RES"
"2","(1350,975)","2","pure_quanta","I4";
;
LOCATION"PR262"
$SEC"1"
CDS_SEC"1"
PACK_TYPE"0402LF"
VALUE"8.87K"
TOLERANCE"1%"
MATERIAL"EMPTY"
WATTAGE"1/16W"
CDS_LIB"pure_quanta"
PART_NUMBER"CS28872FB01";
"A"
$PN"1"56;
"B"
$PN"2"6;
%"Q_CAP"
"1","(5500,1700)","0","pure_quanta","I40";
;
LOCATION"PC413"
$SEC"1"
CDS_SEC"1"
VALUE"0.22UF"
MATERIAL"X7R"
TOLERANCE"10%"
PACK_TYPE"0402"
VOLTAGE"16V"
CDS_LIB"pure_quanta"
PART_NUMBER"CH4223K1B00";
"B"
$PN"2"36;
"A"
$PN"1"19;
%"Q_CAP"
"1","(4475,2375)","0","pure_quanta","I41";
;
LOCATION"PC407_4"
$SEC"1"
CDS_SEC"1"
TOLERANCE"10%"
VALUE"1UF"
VOLTAGE"25V"
PACK_TYPE"C0402"
MATERIAL"X6S"
CDS_LIB"pure_quanta"
PART_NUMBER"CH5104KEB02";
"B"
$PN"2"11;
"A"
$PN"1"12;
%"Q_CAP"
"1","(4875,2375)","0","pure_quanta","I42";
;
LOCATION"PC409_4"
$SEC"1"
CDS_SEC"1"
PACK_TYPE"C0805"
MATERIAL"X6S"
VALUE"22UF"
VOLTAGE"16V"
TOLERANCE"20%"
CDS_LIB"pure_quanta"
PART_NUMBER"CH6223MEA01";
"B"
$PN"2"11;
"A"
$PN"1"12;
%"UNIVERSAL_GND"
"1","(4775,3325)","0","pure_quanta_power","I43";
;
CDS_LIB"pure_quanta_power"
HDL_POWER"GND";
"A"9;
%"Q_RES"
"2","(4775,3550)","0","pure_quanta","I44";
;
LOCATION"PR516"
$SEC"1"
CDS_SEC"1"
WATTAGE"1/8W"
TOLERANCE"1%"
VALUE"1.5"
MATERIAL"EMPTY"
PACK_TYPE"0402LF"
CDS_LIB"pure_quanta"
PART_NUMBER"CS-1504FB00";
"A"
$PN"1"33;
"B"
$PN"2"9;
%"Q_CAP"
"1","(5275,2375)","0","pure_quanta","I45";
;
LOCATION"PC411_4"
$SEC"1"
CDS_SEC"1"
MATERIAL"X6S"
PACK_TYPE"C0805"
VALUE"22UF"
VOLTAGE"16V"
TOLERANCE"20%"
CDS_LIB"pure_quanta"
PART_NUMBER"CH6223MEA01";
"B"
$PN"2"11;
"A"
$PN"1"12;
%"UNIVERSAL_GND"
"1","(5650,2000)","0","pure_quanta_power","I46";
;
CDS_LIB"pure_quanta_power"
HDL_POWER"GND";
"A"11;
%"Q_CAP"
"1","(5650,2375)","0","pure_quanta","I47";
;
LOCATION"PC415_4"
$SEC"1"
CDS_SEC"1"
PACK_TYPE"C0805"
MATERIAL"X6S"
VALUE"22UF"
VOLTAGE"16V"
TOLERANCE"20%"
CDS_LIB"pure_quanta"
PART_NUMBER"CH6223MEA01";
"B"
$PN"2"11;
"A"
$PN"1"12;
%"VCC_CORE"
"1","(5650,2725)","0","pure_quanta_power","I48";
;
HDL_POWER"SW_P12V_AUX_PVDDCR_CPU1_P1_FLT"
CDS_LIB"pure_quanta_power";
"A"12;
%"Q_RES"
"1","(5900,3125)","0","pure_quanta","I49";
;
LOCATION"PR269"
$SEC"1"
CDS_SEC"1"
PACK_TYPE"0402LF"
MATERIAL"CHIP"
WATTAGE"1/16W"
VALUE"0"
TOLERANCE"5%"
CDS_LIB"pure_quanta"
PART_NUMBER"CS00002JB13";
"B"
$PN"2"21;
"A"
$PN"1"13;
%"Q_INDUCTOR4P_14"
"1","(6650,1350)","0","pure_quanta","I50";
;
LOCATION"PL43"
$SEC"1"
CDS_SEC"1"
PART_TYPE"SMLF"
MATERIAL"IND"
VALUE"150NH"
NEEDS_NO_SIZE"TRUE"
CDS_LIB"pure_quanta"
PART_NUMBER"CV+15^0TZ04";
"1"
$PN"1"37;
"4"
$PN"4"23;
"3"
$PN"3"26;
"2"
$PN"2"42;
%"UNIVERSAL_GND"
"1","(7525,1125)","0","pure_quanta_power","I51";
;
CDS_LIB"pure_quanta_power"
HDL_POWER"GND";
"A"26;
%"Q_RES"
"1","(4675,4650)","0","pure_quanta","I52";
;
LOCATION"PR267"
$SEC"1"
CDS_SEC"1"
WATTAGE"1/16W"
TOLERANCE"1%"
PACK_TYPE"0402LF"
VALUE"5.6"
MATERIAL"CHIP"
CDS_LIB"pure_quanta"
PART_NUMBER"CS-5602FB01";
"B"
$PN"2"17;
"A"
$PN"1"20;
%"Q_CAP"
"1","(4775,4100)","0","pure_quanta","I53";
;
LOCATION"PC206"
$SEC"1"
CDS_SEC"1"
VALUE"560PF"
VOLTAGE"50V"
TOLERANCE"10%"
MATERIAL"EMPTY"
PACK_TYPE"C0402"
CDS_LIB"pure_quanta"
PART_NUMBER"CH1566K1B09";
"B"
$PN"2"33;
"A"
$PN"1"14;
%"Q_CAP"
"1","(4525,5225)","0","pure_quanta","I54";
;
LOCATION"PC406_3"
$SEC"1"
CDS_SEC"1"
PACK_TYPE"C0402"
MATERIAL"X6S"
TOLERANCE"10%"
VALUE"1UF"
VOLTAGE"25V"
CDS_LIB"pure_quanta"
PART_NUMBER"CH5104KEB02";
"B"
$PN"2"16;
"A"
$PN"1"25;
%"Q_CAP"
"1","(4925,5225)","0","pure_quanta","I55";
;
LOCATION"PC410_3"
$SEC"1"
CDS_SEC"1"
TOLERANCE"20%"
MATERIAL"X6S"
VOLTAGE"16V"
VALUE"22UF"
PACK_TYPE"C0805"
CDS_LIB"pure_quanta"
PART_NUMBER"CH6223MEA01";
"B"
$PN"2"16;
"A"
$PN"1"25;
%"Q_CAP"
"1","(5650,4525)","0","pure_quanta","I57";
;
LOCATION"PC414"
$SEC"1"
CDS_SEC"1"
VOLTAGE"16V"
MATERIAL"X7R"
VALUE"0.22UF"
TOLERANCE"10%"
PACK_TYPE"0402"
CDS_LIB"pure_quanta"
PART_NUMBER"CH4223K1B00";
"B"
$PN"2"15;
"A"
$PN"1"17;
%"UNIVERSAL_GND"
"1","(5700,4875)","0","pure_quanta_power","I58";
;
CDS_LIB"pure_quanta_power"
HDL_POWER"GND";
"A"16;
%"Q_CAP"
"1","(5325,5225)","0","pure_quanta","I59";
;
LOCATION"PC412_3"
$SEC"1"
CDS_SEC"1"
VOLTAGE"16V"
TOLERANCE"20%"
PACK_TYPE"C0805"
MATERIAL"X6S"
VALUE"22UF"
CDS_LIB"pure_quanta"
PART_NUMBER"CH6223MEA01";
"B"
$PN"2"16;
"A"
$PN"1"25;
%"UNIVERSAL_GND"
"1","(1500,1725)","0","pure_quanta_power","I6";
;
CDS_LIB"pure_quanta_power"
HDL_POWER"GND";
"A"10;
%"Q_CAP"
"1","(5700,5225)","0","pure_quanta","I60";
;
LOCATION"PC416_3"
$SEC"1"
CDS_SEC"1"
MATERIAL"X6S"
TOLERANCE"20%"
VOLTAGE"16V"
PACK_TYPE"C0805"
VALUE"22UF"
CDS_LIB"pure_quanta"
PART_NUMBER"CH6223MEA01";
"B"
$PN"2"16;
"A"
$PN"1"25;
%"VCC_CORE"
"1","(5700,5575)","0","pure_quanta_power","I61";
;
HDL_POWER"SW_P12V_AUX_PVDDCR_CPU1_P1_FLT"
CDS_LIB"pure_quanta_power";
"A"25;
%"Q_INDUCTOR4P_14"
"1","(6700,4175)","0","pure_quanta","I62";
;
LOCATION"PL44"
$SEC"1"
CDS_SEC"1"
PART_TYPE"SMLF"
VALUE"150NH"
MATERIAL"IND"
NEEDS_NO_SIZE"TRUE"
CDS_LIB"pure_quanta"
PART_NUMBER"CV+15^0TZ04";
"1"
$PN"1"14;
"4"
$PN"4"21;
"3"
$PN"3"40;
"2"
$PN"2"41;
%"Q_CAP"
"1","(8175,4100)","0","pure_quanta","I64";
;
LOCATION"PC417_3"
$SEC"1"
CDS_SEC"1"
VOLTAGE"4V"
VALUE"22UF"
TOLERANCE"20%"
MATERIAL"X6S"
PACK_TYPE"C0805"
CDS_LIB"pure_quanta"
PART_NUMBER"CH622KMEA03";
"B"
$PN"2"22;
"A"
$PN"1"21;
%"Q_CAP"
"1","(8325,1275)","0","pure_quanta","I65";
;
LOCATION"PC418_4"
$SEC"1"
CDS_SEC"1"
VOLTAGE"4V"
VALUE"22UF"
TOLERANCE"20%"
MATERIAL"X6S"
PACK_TYPE"C0805"
CDS_LIB"pure_quanta"
PART_NUMBER"CH622KMEA03";
"B"
$PN"2"24;
"A"
$PN"1"23;
%"UNIVERSAL_GND"
"1","(8750,950)","0","pure_quanta_power","I66";
;
CDS_LIB"pure_quanta_power"
HDL_POWER"GND";
"A"24;
%"Q_CAP"
"1","(8750,1275)","0","pure_quanta","I67";
;
LOCATION"PC420_4"
$SEC"1"
CDS_SEC"1"
VOLTAGE"4V"
VALUE"22UF"
TOLERANCE"20%"
MATERIAL"X6S"
PACK_TYPE"C0805"
CDS_LIB"pure_quanta"
PART_NUMBER"CH622KMEA03";
"B"
$PN"2"24;
"A"
$PN"1"23;
%"VCC_CORE"
"1","(8750,1575)","0","pure_quanta_power","I68";
;
HDL_POWER"PVDDCR_CPU1_P1"
CDS_LIB"pure_quanta_power";
"A"23;
%"UNIVERSAL_GND"
"1","(8600,3775)","0","pure_quanta_power","I69";
;
CDS_LIB"pure_quanta_power"
HDL_POWER"GND";
"A"22;
%"Q_CAP"
"1","(1500,1925)","0","pure_quanta","I7";
;
LOCATION"PC399"
$SEC"1"
CDS_SEC"1"
MATERIAL"X6S"
TOLERANCE"10%"
VALUE"2.2UF"
VOLTAGE"10V"
PACK_TYPE"C0402"
CDS_LIB"pure_quanta"
PART_NUMBER"CH5222KEB01";
"B"
$PN"2"10;
"A"
$PN"1"32;
%"Q_CAP"
"1","(8600,4100)","0","pure_quanta","I70";
;
LOCATION"PC419_3"
$SEC"1"
CDS_SEC"1"
VOLTAGE"4V"
VALUE"22UF"
TOLERANCE"20%"
MATERIAL"X6S"
PACK_TYPE"C0805"
CDS_LIB"pure_quanta"
PART_NUMBER"CH622KMEA03";
"B"
$PN"2"22;
"A"
$PN"1"21;
%"VCC_CORE"
"1","(8600,4400)","0","pure_quanta_power","I71";
;
HDL_POWER"PVDDCR_CPU1_P1"
CDS_LIB"pure_quanta_power";
"A"21;
%"ISL99390FRZTR5935"
"1","(3300,4300)","0","pure_quanta","I72";
;
LOCATION"PU37"
$SEC"1"
CDS_SEC"1"
PART_TYPE"SMLF"
MATERIAL"IC"
VALUE"ISL99390FRZ-TR5935"
CDS_LIB"pure_quanta"
CDS_LMAN_SYM_OUTLINE"-300,700,250,-650"
NEEDS_NO_SIZE"TRUE"
PART_NUMBER"AL099390004";
"PGND2"
$PN"7_9-20_24"28;
"GL2"
$PN"41"39;
"GL1"
$PN"6"38;
"DNC"
$PN"31"46;
"EN"
$PN"35"45;
"PGND3"
$PN"40"28;
"VOS"
$PN"1"13;
"VIN2"
$PN"30"25;
"PGND1"
$PN"5"28;
"SW"
$PN"10_19"14;
"LSET"
$PN"37"49;
"IOUT"
$PN"38"48;
"TOUT_FLT"
$PN"36"55;
"PVCC"
$PN"4"27;
"PHASE"
$PN"32"15;
"VIN1"
$PN"25_29"25;
"BOOT"
$PN"33"20;
"AGND"
$PN"2"28;
"VCC"
$PN"3"45;
"REFIN"
$PN"39"47;
"PWM"
$PN"34"54;
END.
